# SA45_DaughterCard-RevX1_bom.xlsx — SA45_DaughterCard-RevX1_bom (bom)
| Designator | Description | Comment | Footprint | Quantity | Manufacturer | Fitted | Manufacturer Part Number |
| C1 | CAP, CER, X5R, 1UF, 10%, 35V, 0402, 0.55MM T | Murata_GRM155R6YA105KE11D | CAPC1005X061N | 1 | Murata | Fitted | GRM155R6YA105KE11D |
| C2, C3, C6, C12 | CAP, CER, X5R, 0.10UF, 10%, 50V, 0402, 0.55MM T | Murata_GRM155R61H104KE14D | CAPC1005X055N | 4 | Murata | Fitted | GRM155R61H104KE14D |
| C4 | CAP, CER, NP0, 33PF, 5%, 25V, 0201, 0.33MM T | Murata_GRM0335C1E330JA01D | CAPC0603X033N | 1 | Murata | Fitted | GRM0335C1E330JA01D |
| C5, C7 | CAP, CER, X5R, 10UF, 10%, 35V, 0805, 1.45MM T | Murata_GRM21BR6YA106KE43L | CAPC2013X145N | 2 | Murata | Fitted | GRM21BR6YA106KE43L |
| C8, C10, C11 | CAP, CER, X5R, 22UF, 20%, 10V, 0805, 1.40MM T | Murata_GRM21BR61A226ME51L | CAPC2013X140N | 3 | Murata | Fitted | GRM21BR61A226ME51L |
| C9 | CAP, CER, X5R, 3300PF, 10%, 10V, 0201, 0.33MM T | Murata_GRM033R61A332KA01D | CAPC0603X033N | 0 | Murata | Not Fitted | GRM033R61A332KA01D |
| J1, J2 | STANDOFF, ROUND, M2X0.4 STEEL 4MM, 9774040243R | Wurth_9774040243R | TH000V_300DIAx400_001mt_9774040243R | 2 | Wurth Elektronik | Fitted | 9774040243R |
| J3, J4, J5, J6 |  | Keystone_4871 | Keystone_4871 | 4 | Keystone Electronics | Fitted | 4871 |
| L1 |  | 4.7uH | Eaton_HCM0703-4R7-R | 1 | Eaton | Fitted | HCM0703-4R7-R |
| P1, P2, P3, P4, P5, P6, P7, P8, P9, P10 | CONN, PC PIN, PRESS-FIT, 10.16MM LENGTH, TIN, TH | Mill-Max_8600-0-05-80-00-00-03-0 | TH001V_109DIA_000mt_8600-0 | 10 | Mill-Max Manufacturing Corp. | Fitted | 8600-0-05-80-00-00-03-0 |
| R1 |  | ERJ-3EKF1003V | RESC1608X55X30ML15T15 | 0 | Panasonic | Not Fitted | ERJ-3EKF1003V |
| R2 | RES SMD 91K OHM 1% 1/16W 0402 | Yageo_RC0402FR-0791KL | RESC1005X040N | 1 | Yageo | Fitted | RC0402FR-0791KL |
| R3 | RES, 0 OHM, 2A, 1/4W, 1206 | Yageo_RC1206JR-070RL | RESC3216X070N | 1 | Yageo | Fitted | RC1206JR-070RL |
| R4 | RES SMD 30K OHM 1% 1/16W 0402 | Yageo_RC0402FR-0730KL | RESC1005X040N | 1 | Yageo | Fitted | RC0402FR-0730KL |
| R5 | RES, 27K OHM, 1%, 1/10W, 100PPM/C, 0402 | Panasonic_ERJ-2RKF2702X | RESC1005X040N | 0 | Panasonic | Not Fitted | ERJ-2RKF2702X |
| R6 | RES, 0.0 OHM, 0.5A, 1/20W, 0201 | Yageo_RC0201JR-070RL | RESC0603X026N | 1 | Yageo | Fitted | RC0201JR-070RL |
| U1 |  | Microchip_SA45 | Microchip_SA45 | 1 | Microchip | Fitted | 090-02984-001 |
| U2 |  | IQD_ICPT-1 | IQD_ICPT-1 | 0 | IQD | Not Fitted | IQD-ICPT-1 |
| U3 |  | DiodesInc_AP63356QZV-7 | DiodesInc_AP63356QZV-7 | 1 | Diodes Incorporated | Fitted | AP63356QZV-7 |
